(kicad_pcb
	(version 20260206)
	(generator "pcbnew")
	(generator_version "10.0")
	(general
		(thickness 1.6)
		(legacy_teardrops no)
	)
	(paper "A4")
	(title_block
		(title "04192023_DAF0TMB3IC0_F0TG_MB_C_brd_V02_OCP.brd")
		(comment 1 "Grand Teton / footprints 6992-6996 of 8354")
	)
	(layers
		(0 "F.Cu" signal "TOP")
		(4 "In1.Cu" signal "GND")
		(6 "In2.Cu" signal "IN1")
		(8 "In3.Cu" signal "GND1")
		(10 "In4.Cu" signal "IN2")
		(12 "In5.Cu" signal "GND2")
		(14 "In6.Cu" signal "IN3")
		(16 "In7.Cu" signal "GND3")
		(18 "In8.Cu" signal "VCC")
		(20 "In9.Cu" signal "VCC1")
		(22 "In10.Cu" signal "GND4")
		(24 "In11.Cu" signal "IN4")
		(26 "In12.Cu" signal "GND5")
		(28 "In13.Cu" signal "IN5")
		(30 "In14.Cu" signal "GND6")
		(32 "In15.Cu" signal "IN6")
		(34 "In16.Cu" signal "GND7")
		(2 "B.Cu" signal "BOTTOM")
		(9 "F.Adhes" user "F.Adhesive")
		(11 "B.Adhes" user "B.Adhesive")
		(13 "F.Paste" user "Package Geometry/Pastemask Top")
		(15 "B.Paste" user "Package Geometry/Pastemask Bottom")
		(5 "F.SilkS" user "Ref Des/Silkscreen Top")
		(7 "B.SilkS" user "Ref Des/Silkscreen Bottom")
		(1 "F.Mask" user "Board Geometry/Soldermask Top")
		(3 "B.Mask" user "Board Geometry/Soldermask Bottom")
		(17 "Dwgs.User" user "User.Drawings")
		(19 "Cmts.User" user "User.Comments")
		(21 "Eco1.User" user "User.Eco1")
		(23 "Eco2.User" user "User.Eco2")
		(25 "Edge.Cuts" user "Board Geometry/Outline")
		(27 "Margin" user)
		(31 "F.CrtYd" user "Package Geometry/Place Bound Top")
		(29 "B.CrtYd" user "Package Geometry/Place Bound Bottom")
		(35 "F.Fab" user "Ref Des/Assembly Top")
		(33 "B.Fab" user "Ref Des/Assembly Bottom")
	)
	(footprint ""
		(layer "B.Cu")
		(at 511.511042 -457.330048 -90)
		(property "Reference" "X9011"
			(at 4.7244 -1.61163 270)
			(unlocked yes)
			(layer "B.SilkS")
			(effects
				(font
					(size 0.7874 0.5842)
					(thickness 0.1524)
				)
				(justify left mirror)
			)
		)
		(property "Value" ""
			(at 0 0 90)
			(layer "B.Fab")
			(effects
				(font
					(size 1.27 1.27)
				)
				(justify mirror)
			)
		)
		(property "User Part Number" "N_A"
			(at -1.30175 1.27 180)
			(unlocked yes)
			(layer "Cmts.User")
			(hide yes)
			(effects
				(font
					(size 0.635 0.4064)
					(thickness 0.1524)
				)
				(justify mirror)
			)
		)
		(property "Device Type" "TP_TDR_4P_FTS_TH-TP_TDR_4P_DIP,EMPTY,TP15"
			(at -1.30175 1.27 180)
			(unlocked yes)
			(layer "B.Fab")
			(hide yes)
			(effects
				(font
					(size 0.635 0.4064)
					(thickness 0.1524)
				)
				(justify mirror)
			)
		)
		(duplicate_pad_numbers_are_jumpers no)
		(fp_line
			(start -2.54 3.81)
			(end -2.54 3.6703)
			(stroke
				(width 0.1524)
				(type default)
			)
			(layer "B.SilkS")
		)
		(fp_line
			(start 0 3.81)
			(end -2.54 3.81)
			(stroke
				(width 0.1524)
				(type default)
			)
			(layer "B.SilkS")
		)
		(fp_line
			(start 0 3.175)
			(end 0 3.81)
			(stroke
				(width 0.1524)
				(type default)
			)
			(layer "B.SilkS")
		)
		(fp_line
			(start -2.54 1.4097)
			(end -2.54 1.1303)
			(stroke
				(width 0.1524)
				(type default)
			)
			(layer "B.SilkS")
		)
		(fp_line
			(start 0 0.635)
			(end 0 1.905)
			(stroke
				(width 0.1524)
				(type default)
			)
			(layer "B.SilkS")
		)
		(fp_line
			(start -2.54 -1.1303)
			(end -2.54 -1.27)
			(stroke
				(width 0.1524)
				(type default)
			)
			(layer "B.SilkS")
		)
		(fp_line
			(start -2.54 -1.27)
			(end 0 -1.27)
			(stroke
				(width 0.1524)
				(type default)
			)
			(layer "B.SilkS")
		)
		(fp_line
			(start 0 -1.27)
			(end 0 -0.635)
			(stroke
				(width 0.1524)
				(type default)
			)
			(layer "B.SilkS")
		)
		(fp_poly
			(pts
				(xy 0.761746 0) (xy 2.285746 -0.762) (xy 2.285746 0.762)
			)
			(stroke
				(width 0)
				(type default)
			)
			(fill yes)
			(layer "B.SilkS")
		)
		(fp_line
			(start -2.54 3.81)
			(end -2.54 -1.27)
			(stroke
				(width 0.1)
				(type default)
			)
			(layer "B.Fab")
		)
		(fp_line
			(start 0 3.81)
			(end -2.54 3.81)
			(stroke
				(width 0.1)
				(type default)
			)
			(layer "B.Fab")
		)
		(fp_line
			(start -2.54 -1.27)
			(end 0 -1.27)
			(stroke
				(width 0.1)
				(type default)
			)
			(layer "B.Fab")
		)
		(fp_line
			(start 0 -1.27)
			(end 0 3.81)
			(stroke
				(width 0.1)
				(type default)
			)
			(layer "B.Fab")
		)
		(fp_poly
			(pts
				(xy 0.761746 0) (xy 2.285746 -0.762) (xy 2.285746 0.762)
			)
			(stroke
				(width 0)
				(type default)
			)
			(fill yes)
			(layer "B.Fab")
		)
		(pad "1" thru_hole circle
			(at 0 0 90)
			(size 1.0033 1.0033)
			(drill 0.249936)
			(layers "*.Cu" "*.Mask")
			(remove_unused_layers no)
			(net "TDR_DIFF_85_NECK_IN4_DN")
			(clearance 0.10795)
			(padstack
				(mode front_inner_back)
				(layer "Inner"
					(shape circle)
					(size 0.8001 0.8001)
					(clearance 0.1524)
				)
				(layer "B.Cu"
					(shape circle)
					(size 1.0033 1.0033)
					(thermal_gap 0.10795)
					(clearance 0.10795)
				)
			)
		)
		(pad "2" thru_hole circle
			(at -2.54 0 90)
			(size 1.9939 1.9939)
			(drill 0.249936)
			(layers "*.Cu" "*.Mask")
			(remove_unused_layers no)
			(net "T1_GND")
			(clearance 0.10795)
			(padstack
				(mode front_inner_back)
				(layer "Inner"
					(shape circle)
					(size 0.8001 0.8001)
					(clearance 0.1524)
				)
				(layer "B.Cu"
					(shape circle)
					(size 1.9939 1.9939)
					(thermal_gap 0.10795)
					(clearance 0.10795)
				)
			)
		)
		(pad "3" thru_hole circle
			(at -2.54 2.54 90)
			(size 1.9939 1.9939)
			(drill 0.249936)
			(layers "*.Cu" "*.Mask")
			(remove_unused_layers no)
			(net "T1_GND")
			(clearance 0.10795)
			(padstack
				(mode front_inner_back)
				(layer "Inner"
					(shape circle)
					(size 0.8001 0.8001)
					(clearance 0.1524)
				)
				(layer "B.Cu"
					(shape circle)
					(size 1.9939 1.9939)
					(thermal_gap 0.10795)
					(clearance 0.10795)
				)
			)
		)
		(pad "4" thru_hole circle
			(at 0 2.54 90)
			(size 1.0033 1.0033)
			(drill 0.249936)
			(layers "*.Cu" "*.Mask")
			(remove_unused_layers no)
			(net "TDR_DIFF_85_NECK_IN4_DP")
			(clearance 0.10795)
			(padstack
				(mode front_inner_back)
				(layer "Inner"
					(shape circle)
					(size 0.8001 0.8001)
					(clearance 0.1524)
				)
				(layer "B.Cu"
					(shape circle)
					(size 1.0033 1.0033)
					(thermal_gap 0.10795)
					(clearance 0.10795)
				)
			)
		)
	)
	(footprint ""
		(layer "B.Cu")
		(at 312.443876 -66.708782 90)
		(property "Reference" "R3069"
			(at 0 0 90)
			(layer "B.SilkS")
			(hide yes)
			(effects
				(font
					(size 1.27 1.27)
				)
				(justify mirror)
			)
		)
		(property "Value" ""
			(at 0 0 90)
			(layer "B.Fab")
			(effects
				(font
					(size 1.27 1.27)
				)
				(justify mirror)
			)
		)
		(duplicate_pad_numbers_are_jumpers no)
		(fp_line
			(start 0.7874 -0.4064)
			(end -0.7874 -0.4064)
			(stroke
				(width 0.1524)
				(type default)
			)
			(layer "B.SilkS")
		)
		(fp_line
			(start -0.7874 -0.4064)
			(end -0.7874 0.4064)
			(stroke
				(width 0.1524)
				(type default)
			)
			(layer "B.SilkS")
		)
		(fp_line
			(start 0.7874 0.4064)
			(end 0.7874 -0.4064)
			(stroke
				(width 0.1524)
				(type default)
			)
			(layer "B.SilkS")
		)
		(fp_line
			(start -0.7874 0.4064)
			(end 0.7874 0.4064)
			(stroke
				(width 0.1524)
				(type default)
			)
			(layer "B.SilkS")
		)
		(fp_line
			(start 0.67945 -0.305054)
			(end 0.12065 -0.305054)
			(stroke
				(width 0.1)
				(type default)
			)
			(layer "B.Fab")
		)
		(fp_line
			(start 0.12065 -0.305054)
			(end 0.12065 -0.2794)
			(stroke
				(width 0.1)
				(type default)
			)
			(layer "B.Fab")
		)
		(fp_line
			(start -0.12065 -0.3048)
			(end -0.67945 -0.3048)
			(stroke
				(width 0.1)
				(type default)
			)
			(layer "B.Fab")
		)
		(fp_line
			(start -0.67945 -0.3048)
			(end -0.67945 0.3048)
			(stroke
				(width 0.1)
				(type default)
			)
			(layer "B.Fab")
		)
		(fp_line
			(start 0.12065 -0.2794)
			(end -0.12065 -0.2794)
			(stroke
				(width 0.1)
				(type default)
			)
			(layer "B.Fab")
		)
		(fp_line
			(start -0.12065 -0.2794)
			(end -0.12065 -0.3048)
			(stroke
				(width 0.1)
				(type default)
			)
			(layer "B.Fab")
		)
		(fp_line
			(start 0.12065 0.2794)
			(end 0.12065 0.3048)
			(stroke
				(width 0.1)
				(type default)
			)
			(layer "B.Fab")
		)
		(fp_line
			(start -0.120396 0.2794)
			(end 0.12065 0.2794)
			(stroke
				(width 0.1)
				(type default)
			)
			(layer "B.Fab")
		)
		(fp_line
			(start 0.67945 0.3048)
			(end 0.67945 -0.305054)
			(stroke
				(width 0.1)
				(type default)
			)
			(layer "B.Fab")
		)
		(fp_line
			(start 0.12065 0.3048)
			(end 0.67945 0.3048)
			(stroke
				(width 0.1)
				(type default)
			)
			(layer "B.Fab")
		)
		(fp_line
			(start -0.120396 0.3048)
			(end -0.120396 0.2794)
			(stroke
				(width 0.1)
				(type default)
			)
			(layer "B.Fab")
		)
		(fp_line
			(start -0.67945 0.3048)
			(end -0.120396 0.3048)
			(stroke
				(width 0.1)
				(type default)
			)
			(layer "B.Fab")
		)
		(pad "1" smd circle
			(at 0.40005 0 270)
			(size 0 0)
			(layers "B.Cu" "B.Mask" "B.Paste")
			(net "LED_PWRGD_SYS_PWROK_R")
		)
		(pad "2" smd circle
			(at -0.40005 0 270)
			(size 0 0)
			(layers "B.Cu" "B.Mask" "B.Paste")
			(net "P3V3_AUX")
		)
	)
	(footprint ""
		(layer "B.Cu")
		(at 355.272848 -398.942052 90)
		(property "Reference" "C663"
			(at 0 0 90)
			(layer "B.SilkS")
			(hide yes)
			(effects
				(font
					(size 1.27 1.27)
				)
				(justify mirror)
			)
		)
		(property "Value" ""
			(at 0 0 90)
			(layer "B.Fab")
			(effects
				(font
					(size 1.27 1.27)
				)
				(justify mirror)
			)
		)
		(duplicate_pad_numbers_are_jumpers no)
		(fp_line
			(start 0.7874 -0.4064)
			(end -0.7874 -0.4064)
			(stroke
				(width 0.1524)
				(type default)
			)
			(layer "B.SilkS")
		)
		(fp_line
			(start -0.7874 -0.4064)
			(end -0.7874 0.4064)
			(stroke
				(width 0.1524)
				(type default)
			)
			(layer "B.SilkS")
		)
		(fp_line
			(start 0.7874 0.4064)
			(end 0.7874 -0.4064)
			(stroke
				(width 0.1524)
				(type default)
			)
			(layer "B.SilkS")
		)
		(fp_line
			(start -0.7874 0.4064)
			(end 0.7874 0.4064)
			(stroke
				(width 0.1524)
				(type default)
			)
			(layer "B.SilkS")
		)
		(fp_line
			(start 0.67945 -0.305054)
			(end 0.12065 -0.305054)
			(stroke
				(width 0.1)
				(type default)
			)
			(layer "B.Fab")
		)
		(fp_line
			(start 0.12065 -0.305054)
			(end 0.12065 -0.2794)
			(stroke
				(width 0.1)
				(type default)
			)
			(layer "B.Fab")
		)
		(fp_line
			(start -0.12065 -0.3048)
			(end -0.67945 -0.3048)
			(stroke
				(width 0.1)
				(type default)
			)
			(layer "B.Fab")
		)
		(fp_line
			(start -0.67945 -0.3048)
			(end -0.67945 0.3048)
			(stroke
				(width 0.1)
				(type default)
			)
			(layer "B.Fab")
		)
		(fp_line
			(start 0.12065 -0.2794)
			(end -0.12065 -0.2794)
			(stroke
				(width 0.1)
				(type default)
			)
			(layer "B.Fab")
		)
		(fp_line
			(start -0.12065 -0.2794)
			(end -0.12065 -0.3048)
			(stroke
				(width 0.1)
				(type default)
			)
			(layer "B.Fab")
		)
		(fp_line
			(start 0.12065 0.2794)
			(end 0.12065 0.3048)
			(stroke
				(width 0.1)
				(type default)
			)
			(layer "B.Fab")
		)
		(fp_line
			(start -0.120396 0.2794)
			(end 0.12065 0.2794)
			(stroke
				(width 0.1)
				(type default)
			)
			(layer "B.Fab")
		)
		(fp_line
			(start 0.67945 0.3048)
			(end 0.67945 -0.305054)
			(stroke
				(width 0.1)
				(type default)
			)
			(layer "B.Fab")
		)
		(fp_line
			(start 0.12065 0.3048)
			(end 0.67945 0.3048)
			(stroke
				(width 0.1)
				(type default)
			)
			(layer "B.Fab")
		)
		(fp_line
			(start -0.120396 0.3048)
			(end -0.120396 0.2794)
			(stroke
				(width 0.1)
				(type default)
			)
			(layer "B.Fab")
		)
		(fp_line
			(start -0.67945 0.3048)
			(end -0.120396 0.3048)
			(stroke
				(width 0.1)
				(type default)
			)
			(layer "B.Fab")
		)
		(pad "1" smd circle
			(at 0.40005 0 270)
			(size 0 0)
			(layers "B.Cu" "B.Mask" "B.Paste")
			(net "P0V9_CPU0_RT1_2A")
		)
		(pad "2" smd circle
			(at -0.40005 0 270)
			(size 0 0)
			(layers "B.Cu" "B.Mask" "B.Paste")
			(net "GND")
		)
	)
	(footprint ""
		(layer "B.Cu")
		(at 51.415442 -421.17518)
		(property "Reference" "C1881"
			(at 0 0 0)
			(layer "B.SilkS")
			(hide yes)
			(effects
				(font
					(size 1.27 1.27)
				)
				(justify mirror)
			)
		)
		(property "Value" ""
			(at 0 0 0)
			(layer "B.Fab")
			(effects
				(font
					(size 1.27 1.27)
				)
				(justify mirror)
			)
		)
		(duplicate_pad_numbers_are_jumpers no)
		(fp_line
			(start -0.7874 -0.4064)
			(end -0.7874 0.4064)
			(stroke
				(width 0.1524)
				(type default)
			)
			(layer "B.SilkS")
		)
		(fp_line
			(start -0.7874 0.4064)
			(end 0.7874 0.4064)
			(stroke
				(width 0.1524)
				(type default)
			)
			(layer "B.SilkS")
		)
		(fp_line
			(start 0.7874 -0.4064)
			(end -0.7874 -0.4064)
			(stroke
				(width 0.1524)
				(type default)
			)
			(layer "B.SilkS")
		)
		(fp_line
			(start 0.7874 0.4064)
			(end 0.7874 -0.4064)
			(stroke
				(width 0.1524)
				(type default)
			)
			(layer "B.SilkS")
		)
		(fp_line
			(start -0.67945 -0.3048)
			(end -0.67945 0.3048)
			(stroke
				(width 0.1)
				(type default)
			)
			(layer "B.Fab")
		)
		(fp_line
			(start -0.67945 0.3048)
			(end -0.120396 0.3048)
			(stroke
				(width 0.1)
				(type default)
			)
			(layer "B.Fab")
		)
		(fp_line
			(start -0.12065 -0.3048)
			(end -0.67945 -0.3048)
			(stroke
				(width 0.1)
				(type default)
			)
			(layer "B.Fab")
		)
		(fp_line
			(start -0.12065 -0.2794)
			(end -0.12065 -0.3048)
			(stroke
				(width 0.1)
				(type default)
			)
			(layer "B.Fab")
		)
		(fp_line
			(start -0.120396 0.2794)
			(end 0.12065 0.2794)
			(stroke
				(width 0.1)
				(type default)
			)
			(layer "B.Fab")
		)
		(fp_line
			(start -0.120396 0.3048)
			(end -0.120396 0.2794)
			(stroke
				(width 0.1)
				(type default)
			)
			(layer "B.Fab")
		)
		(fp_line
			(start 0.12065 -0.305054)
			(end 0.12065 -0.2794)
			(stroke
				(width 0.1)
				(type default)
			)
			(layer "B.Fab")
		)
		(fp_line
			(start 0.12065 -0.2794)
			(end -0.12065 -0.2794)
			(stroke
				(width 0.1)
				(type default)
			)
			(layer "B.Fab")
		)
		(fp_line
			(start 0.12065 0.2794)
			(end 0.12065 0.3048)
			(stroke
				(width 0.1)
				(type default)
			)
			(layer "B.Fab")
		)
		(fp_line
			(start 0.12065 0.3048)
			(end 0.67945 0.3048)
			(stroke
				(width 0.1)
				(type default)
			)
			(layer "B.Fab")
		)
		(fp_line
			(start 0.67945 -0.305054)
			(end 0.12065 -0.305054)
			(stroke
				(width 0.1)
				(type default)
			)
			(layer "B.Fab")
		)
		(fp_line
			(start 0.67945 0.3048)
			(end 0.67945 -0.305054)
			(stroke
				(width 0.1)
				(type default)
			)
			(layer "B.Fab")
		)
		(pad "1" smd circle
			(at 0.40005 0 180)
			(size 0 0)
			(layers "B.Cu" "B.Mask" "B.Paste")
			(net "GPU_FPGA_READY_ISO")
		)
		(pad "2" smd circle
			(at -0.40005 0 180)
			(size 0 0)
			(layers "B.Cu" "B.Mask" "B.Paste")
			(net "GND")
		)
	)
	(footprint ""
		(layer "B.Cu")
		(at 108.907834 -271.395952)
		(property "Reference" "C2357"
			(at 0 0 0)
			(layer "B.SilkS")
			(hide yes)
			(effects
				(font
					(size 1.27 1.27)
				)
				(justify mirror)
			)
		)
		(property "Value" ""
			(at 0 0 0)
			(layer "B.Fab")
			(effects
				(font
					(size 1.27 1.27)
				)
				(justify mirror)
			)
		)
		(duplicate_pad_numbers_are_jumpers no)
		(fp_line
			(start -0.7874 -0.4064)
			(end -0.7874 0.4064)
			(stroke
				(width 0.1524)
				(type default)
			)
			(layer "B.SilkS")
		)
		(fp_line
			(start -0.7874 0.4064)
			(end 0.7874 0.4064)
			(stroke
				(width 0.1524)
				(type default)
			)
			(layer "B.SilkS")
		)
		(fp_line
			(start 0.7874 -0.4064)
			(end -0.7874 -0.4064)
			(stroke
				(width 0.1524)
				(type default)
			)
			(layer "B.SilkS")
		)
		(fp_line
			(start 0.7874 0.4064)
			(end 0.7874 -0.4064)
			(stroke
				(width 0.1524)
				(type default)
			)
			(layer "B.SilkS")
		)
		(fp_line
			(start -0.67945 -0.3048)
			(end -0.67945 0.3048)
			(stroke
				(width 0.1)
				(type default)
			)
			(layer "B.Fab")
		)
		(fp_line
			(start -0.67945 0.3048)
			(end -0.120396 0.3048)
			(stroke
				(width 0.1)
				(type default)
			)
			(layer "B.Fab")
		)
		(fp_line
			(start -0.12065 -0.3048)
			(end -0.67945 -0.3048)
			(stroke
				(width 0.1)
				(type default)
			)
			(layer "B.Fab")
		)
		(fp_line
			(start -0.12065 -0.2794)
			(end -0.12065 -0.3048)
			(stroke
				(width 0.1)
				(type default)
			)
			(layer "B.Fab")
		)
		(fp_line
			(start -0.120396 0.2794)
			(end 0.12065 0.2794)
			(stroke
				(width 0.1)
				(type default)
			)
			(layer "B.Fab")
		)
		(fp_line
			(start -0.120396 0.3048)
			(end -0.120396 0.2794)
			(stroke
				(width 0.1)
				(type default)
			)
			(layer "B.Fab")
		)
		(fp_line
			(start 0.12065 -0.305054)
			(end 0.12065 -0.2794)
			(stroke
				(width 0.1)
				(type default)
			)
			(layer "B.Fab")
		)
		(fp_line
			(start 0.12065 -0.2794)
			(end -0.12065 -0.2794)
			(stroke
				(width 0.1)
				(type default)
			)
			(layer "B.Fab")
		)
		(fp_line
			(start 0.12065 0.2794)
			(end 0.12065 0.3048)
			(stroke
				(width 0.1)
				(type default)
			)
			(layer "B.Fab")
		)
		(fp_line
			(start 0.12065 0.3048)
			(end 0.67945 0.3048)
			(stroke
				(width 0.1)
				(type default)
			)
			(layer "B.Fab")
		)
		(fp_line
			(start 0.67945 -0.305054)
			(end 0.12065 -0.305054)
			(stroke
				(width 0.1)
				(type default)
			)
			(layer "B.Fab")
		)
		(fp_line
			(start 0.67945 0.3048)
			(end 0.67945 -0.305054)
			(stroke
				(width 0.1)
				(type default)
			)
			(layer "B.Fab")
		)
		(pad "1" smd circle
			(at 0.40005 0 180)
			(size 0 0)
			(layers "B.Cu" "B.Mask" "B.Paste")
			(net "PVDDCR_CPU1_P1")
		)
		(pad "2" smd circle
			(at -0.40005 0 180)
			(size 0 0)
			(layers "B.Cu" "B.Mask" "B.Paste")
			(net "GND")
		)
	)
)
